# S9S_MB_2U (Grand Teton) — schematic netlist excerpt (pin names and nets, part order shuffled) for the footprints in the layout excerpt that follows; sources: Cadence DE-HDL packaged netlist, KiCad conversion of 03242023_DA0F0TMBIJ0_F0T_Motherboard_J_brd_V01_OCP.brd

ME29  ME_DUMMY_SYMBOL  SNLABEL_15X5 EMPTY  pkg SNLABEL_15X5  page 312
H44  HOLE  EMPTY  pkg TH  page 311 : \1\ = GND
C755  Q_CAP_DIFFBUS  DIFF BUS_0.22UF 6.3V 20% X6S  pkg C0201  page 176 : \1\ = P5E_CPU1_PE2_TX_C_DP<9> ; \2\ = P5E_CPU1_PE2_TX_DP<9>
R3196  Q_RES  22 1% CHIP  pkg 0402LF  page 207 : A = CLK_100M_OCP_V3_2_B_R_DP ; B = CLK_100M_OCP_V3_2_B_DP

(kicad_pcb
	(version 20260206)
	(generator "pcbnew")
	(generator_version "10.0")
	(general
		(thickness 1.6)
		(legacy_teardrops no)
	)
	(paper "A4")
	(title_block
		(title "03242023_DA0F0TMBIJ0_F0T_Motherboard_J_brd_V01_OCP.brd")
		(comment 1 "Grand Teton / footprints 2870-2873 of 6105")
	)
	(layers
		(0 "F.Cu" signal "TOP")
		(4 "In1.Cu" signal "GND")
		(6 "In2.Cu" signal "IN1")
		(8 "In3.Cu" signal "GND1")
		(10 "In4.Cu" signal "IN2")
		(12 "In5.Cu" signal "GND2")
		(14 "In6.Cu" signal "IN3")
		(16 "In7.Cu" signal "GND3")
		(18 "In8.Cu" signal "VCC")
		(20 "In9.Cu" signal "VCC1")
		(22 "In10.Cu" signal "GND4")
		(24 "In11.Cu" signal "IN4")
		(26 "In12.Cu" signal "GND5")
		(28 "In13.Cu" signal "IN5")
		(30 "In14.Cu" signal "GND6")
		(32 "In15.Cu" signal "IN6")
		(34 "In16.Cu" signal "GND7")
		(2 "B.Cu" signal "BOTTOM")
		(9 "F.Adhes" user "F.Adhesive")
		(11 "B.Adhes" user "B.Adhesive")
		(13 "F.Paste" user "Package Geometry/Pastemask Top")
		(15 "B.Paste" user "Package Geometry/Pastemask Bottom")
		(5 "F.SilkS" user "Ref Des/Silkscreen Top")
		(7 "B.SilkS" user "Ref Des/Silkscreen Bottom")
		(1 "F.Mask" user "Board Geometry/Soldermask Top")
		(3 "B.Mask" user "Board Geometry/Soldermask Bottom")
		(17 "Dwgs.User" user "User.Drawings")
		(19 "Cmts.User" user "User.Comments")
		(21 "Eco1.User" user "User.Eco1")
		(23 "Eco2.User" user "User.Eco2")
		(25 "Edge.Cuts" user "Board Geometry/Outline")
		(27 "Margin" user)
		(31 "F.CrtYd" user "Package Geometry/Place Bound Top")
		(29 "B.CrtYd" user "Package Geometry/Place Bound Bottom")
		(35 "F.Fab" user "Ref Des/Assembly Top")
		(33 "B.Fab" user "Ref Des/Assembly Bottom")
	)
	(footprint ""
		(layer "F.Cu")
		(at 237.171738 -119.183658 -90)
		(property "Reference" "R3196"
			(at 0 0 270)
			(layer "F.SilkS")
			(hide yes)
			(effects
				(font
					(size 1.27 1.27)
				)
			)
		)
		(property "Value" ""
			(at 0 0 270)
			(layer "F.Fab")
			(effects
				(font
					(size 1.27 1.27)
				)
			)
		)
		(duplicate_pad_numbers_are_jumpers no)
		(fp_line
			(start -0.7874 0.4064)
			(end -0.7874 -0.064262)
			(stroke
				(width 0.1524)
				(type default)
			)
			(layer "F.SilkS")
		)
		(fp_line
			(start 0.7874 0.4064)
			(end -0.7874 0.4064)
			(stroke
				(width 0.1524)
				(type default)
			)
			(layer "F.SilkS")
		)
		(fp_line
			(start 0.7874 -0.016002)
			(end 0.7874 0.4064)
			(stroke
				(width 0.1524)
				(type default)
			)
			(layer "F.SilkS")
		)
		(fp_line
			(start -0.287782 -0.4064)
			(end 0.438658 -0.4064)
			(stroke
				(width 0.1524)
				(type default)
			)
			(layer "F.SilkS")
		)
		(fp_line
			(start -0.67945 0.3048)
			(end -0.67945 -0.305054)
			(stroke
				(width 0.1)
				(type default)
			)
			(layer "F.Fab")
		)
		(fp_line
			(start -0.12065 0.3048)
			(end -0.67945 0.3048)
			(stroke
				(width 0.1)
				(type default)
			)
			(layer "F.Fab")
		)
		(fp_line
			(start 0.120396 0.3048)
			(end 0.120396 0.2794)
			(stroke
				(width 0.1)
				(type default)
			)
			(layer "F.Fab")
		)
		(fp_line
			(start 0.67945 0.3048)
			(end 0.120396 0.3048)
			(stroke
				(width 0.1)
				(type default)
			)
			(layer "F.Fab")
		)
		(fp_line
			(start -0.12065 0.2794)
			(end -0.12065 0.3048)
			(stroke
				(width 0.1)
				(type default)
			)
			(layer "F.Fab")
		)
		(fp_line
			(start 0.120396 0.2794)
			(end -0.12065 0.2794)
			(stroke
				(width 0.1)
				(type default)
			)
			(layer "F.Fab")
		)
		(fp_line
			(start -0.12065 -0.2794)
			(end 0.12065 -0.2794)
			(stroke
				(width 0.1)
				(type default)
			)
			(layer "F.Fab")
		)
		(fp_line
			(start 0.12065 -0.2794)
			(end 0.12065 -0.3048)
			(stroke
				(width 0.1)
				(type default)
			)
			(layer "F.Fab")
		)
		(fp_line
			(start 0.12065 -0.3048)
			(end 0.67945 -0.3048)
			(stroke
				(width 0.1)
				(type default)
			)
			(layer "F.Fab")
		)
		(fp_line
			(start 0.67945 -0.3048)
			(end 0.67945 0.3048)
			(stroke
				(width 0.1)
				(type default)
			)
			(layer "F.Fab")
		)
		(fp_line
			(start -0.67945 -0.305054)
			(end -0.12065 -0.305054)
			(stroke
				(width 0.1)
				(type default)
			)
			(layer "F.Fab")
		)
		(fp_line
			(start -0.12065 -0.305054)
			(end -0.12065 -0.2794)
			(stroke
				(width 0.1)
				(type default)
			)
			(layer "F.Fab")
		)
		(pad "1" smd circle
			(at -0.40005 0 270)
			(size 0 0)
			(layers "F.Cu" "F.Mask" "F.Paste")
			(net "CLK_100M_OCP_V3_2_B_R_DP")
		)
		(pad "2" smd circle
			(at 0.40005 0 270)
			(size 0 0)
			(layers "F.Cu" "F.Mask" "F.Paste")
			(net "CLK_100M_OCP_V3_2_B_DP")
		)
	)
	(footprint ""
		(layer "F.Cu")
		(at 138.508994 -402.371052 -90)
		(property "Reference" "C755"
			(at 0 0 270)
			(layer "F.SilkS")
			(hide yes)
			(effects
				(font
					(size 1.27 1.27)
				)
			)
		)
		(property "Value" ""
			(at 0 0 270)
			(layer "F.Fab")
			(effects
				(font
					(size 1.27 1.27)
				)
			)
		)
		(duplicate_pad_numbers_are_jumpers no)
		(fp_line
			(start -0.299974 0.150114)
			(end -0.299974 -0.150114)
			(stroke
				(width 0.1)
				(type default)
			)
			(layer "F.Fab")
		)
		(fp_line
			(start 0.299974 0.150114)
			(end -0.299974 0.150114)
			(stroke
				(width 0.1)
				(type default)
			)
			(layer "F.Fab")
		)
		(fp_line
			(start -0.299974 -0.150114)
			(end 0.299974 -0.150114)
			(stroke
				(width 0.1)
				(type default)
			)
			(layer "F.Fab")
		)
		(fp_line
			(start 0.299974 -0.150114)
			(end 0.299974 0.150114)
			(stroke
				(width 0.1)
				(type default)
			)
			(layer "F.Fab")
		)
		(pad "1" smd rect
			(at -0.2667 0 270)
			(size 0.3048 0.381)
			(layers "F.Cu" "F.Mask" "F.Paste")
			(net "P5E_CPU1_PE2_TX_C_DP<9>")
		)
		(pad "2" smd rect
			(at 0.2667 0 270)
			(size 0.3048 0.381)
			(layers "F.Cu" "F.Mask" "F.Paste")
			(net "P5E_CPU1_PE2_TX_DP<9>")
		)
	)
	(footprint ""
		(layer "F.Cu")
		(at 384.458972 -354.434902)
		(property "Reference" "H44"
			(at -3.03276 -5.138928 0)
			(unlocked yes)
			(layer "F.SilkS")
			(effects
				(font
					(size 0.7874 0.5842)
					(thickness 0.1524)
				)
				(justify left)
			)
		)
		(property "Value" ""
			(at 0 0 0)
			(layer "F.Fab")
			(effects
				(font
					(size 1.27 1.27)
				)
			)
		)
		(duplicate_pad_numbers_are_jumpers no)
		(pad "1" thru_hole circle
			(at 0 0)
			(size 8.001 8.001)
			(drill 3.2004)
			(layers "*.Cu" "*.Mask")
			(remove_unused_layers no)
			(net "GND")
			(clearance -2.1463)
			(padstack
				(mode front_inner_back)
				(layer "Inner"
					(shape circle)
					(size 5.0038 5.0038)
					(clearance -0.6477)
				)
				(layer "B.Cu"
					(shape circle)
					(size 8.001 8.001)
					(clearance -2.1463)
				)
			)
		)
	)
	(footprint ""
		(layer "F.Cu")
		(at 31.503366 -48.385476)
		(property "Reference" "ME29"
			(at 0 0 0)
			(layer "F.SilkS")
			(hide yes)
			(effects
				(font
					(size 1.27 1.27)
				)
			)
		)
		(property "Value" ""
			(at 0 0 0)
			(layer "F.Fab")
			(effects
				(font
					(size 1.27 1.27)
				)
			)
		)
		(duplicate_pad_numbers_are_jumpers no)
		(fp_line
			(start 0 -4.99999)
			(end 0 -3.47599)
			(stroke
				(width 0.1524)
				(type default)
			)
			(layer "F.SilkS")
		)
		(fp_line
			(start 0 -0.524002)
			(end 0 0.999998)
			(stroke
				(width 0.1524)
				(type default)
			)
			(layer "F.SilkS")
		)
		(fp_line
			(start 0 0.999998)
			(end 1.524 0.999998)
			(stroke
				(width 0.1524)
				(type default)
			)
			(layer "F.SilkS")
		)
		(fp_line
			(start 1.524 -4.99999)
			(end 0 -4.99999)
			(stroke
				(width 0.1524)
				(type default)
			)
			(layer "F.SilkS")
		)
		(fp_line
			(start 15.475966 0.999998)
			(end 16.999966 0.999998)
			(stroke
				(width 0.1524)
				(type default)
			)
			(layer "F.SilkS")
		)
		(fp_line
			(start 16.999966 -4.99999)
			(end 15.475966 -4.99999)
			(stroke
				(width 0.1524)
				(type default)
			)
			(layer "F.SilkS")
		)
		(fp_line
			(start 16.999966 -3.47599)
			(end 16.999966 -4.99999)
			(stroke
				(width 0.1524)
				(type default)
			)
			(layer "F.SilkS")
		)
		(fp_line
			(start 16.999966 0.999998)
			(end 16.999966 -0.524002)
			(stroke
				(width 0.1524)
				(type default)
			)
			(layer "F.SilkS")
		)
		(fp_text user "S/N"
			(at 0.1016 -3.54965 0)
			(unlocked yes)
			(layer "F.SilkS")
			(effects
				(font
					(size 1.905 1.4224)
					(thickness 0.1524)
				)
				(justify left)
			)
		)
	)
)
